FILE_TYPE = MACRO_DRAWING;
SET COLOR_WIRE YELLOW;
SET COLOR_PROP ORANGE;
SET COLOR_DOT WHITE;
SET COLOR_ARC YELLOW;
SET COLOR_BODY GREEN;
SET COLOR_NOTE PURPLE;
SET PROP_DISPLAY VALUE;
SET PAGE_NUMBER P118;
FORCEADD OFFPAGE..2
(925 -225);
FORCEPROP 2 LAST $XR0 226 
J 0
(1114 -225);
DISPLAY 0.638298 (1114 -225);
PAINT MONO (1114 -225);
FORCEPROP 2 LAST CDS_LIB standard
J 0
(925 -225);
DISPLAY INVISIBLE (925 -225);
FORCEPROP 1 LAST OFFPAGE TRUE
J 0
(1250 -350);
DISPLAY 0.872340 (1250 -350);
PAINT GREEN (1250 -350);
DISPLAY INVISIBLE (1250 -350);
FORCEPROP 1 LAST COMMENT_BODY TRUE
J 0
(880 -320);
DISPLAY 0.872340 (880 -320);
PAINT GREEN (880 -320);
DISPLAY INVISIBLE (880 -320);
FORCEPROP 2 LAST PATH I100
J 0
(1275 -175);
DISPLAY 1.021277 (1275 -175);
DISPLAY INVISIBLE (1275 -175);
FORCEADD Q_RES..1
(-1400 -225);
FORCEPROP 1 LAST PART_NUMBER CS00002JB13
J 0
(-1450 -175);
DISPLAY 0.404255 (-1450 -175);
DISPLAY INVISIBLE (-1450 -175);
FORCEPROP 1 LAST MATERIAL CHIP
J 0
(-1450 -150);
DISPLAY 0.404255 (-1450 -150);
FORCEPROP 1 LAST VALUE 0
J 2
(-1250 -225);
DISPLAY 0.510638 (-1250 -225);
FORCEPROP 1 LAST TOLERANCE 5%
J 0
(-1225 -225);
DISPLAY 0.510638 (-1225 -225);
FORCEPROP 1 LAST PACK_TYPE 0402LF
J 0
(-1450 -125);
DISPLAY 0.404255 (-1450 -125);
FORCEPROP 1 LAST WATTAGE 1/16W
J 2
(-1225 -150);
DISPLAY 0.404255 (-1225 -150);
FORCEPROP 1 LAST LOCATION R302
J 0
(-1600 -225);
DISPLAY 0.638298 (-1600 -225);
FORCEPROP 1 LASTPIN (-1500 -225) $PN 1
J 0
(-1488 -213);
DISPLAY 0.787234 (-1488 -213);
PAINT MONO (-1488 -213);
FORCEPROP 1 LASTPIN (-1300 -225) $PN 2
J 0
(-1338 -213);
DISPLAY 0.787234 (-1338 -213);
PAINT MONO (-1338 -213);
FORCEPROP 2 LAST CDS_LIB pure_quanta
J 0
(-1400 -225);
DISPLAY INVISIBLE (-1400 -225);
FORCEPROP 1 LAST PATH I101
J 0
(-1450 -75);
DISPLAY 0.978723 (-1450 -75);
PAINT WHITE (-1450 -75);
DISPLAY INVISIBLE (-1450 -75);
FORCEPROP 0 LAST $SEC 1
J 0
(-1450 -100);
DISPLAY 0.680851 (-1450 -100);
PAINT MONO (-1450 -100);
DISPLAY INVISIBLE (-1450 -100);
FORCEPROP 0 LAST CDS_SEC 1
J 0
(-1450 -100);
DISPLAY 1.021277 (-1450 -100);
DISPLAY INVISIBLE (-1450 -100);
FORCEADD Q_RES..1
(-1400 -700);
FORCEPROP 1 LAST PART_NUMBER CS00002JB13
J 0
(-1450 -650);
DISPLAY 0.404255 (-1450 -650);
DISPLAY INVISIBLE (-1450 -650);
FORCEPROP 1 LAST MATERIAL CHIP
J 0
(-1450 -625);
DISPLAY 0.404255 (-1450 -625);
FORCEPROP 1 LAST PACK_TYPE 0402LF
J 0
(-1450 -600);
DISPLAY 0.404255 (-1450 -600);
FORCEPROP 1 LAST VALUE 0
J 2
(-1250 -700);
DISPLAY 0.510638 (-1250 -700);
FORCEPROP 1 LAST TOLERANCE 5%
J 0
(-1225 -700);
DISPLAY 0.510638 (-1225 -700);
FORCEPROP 1 LAST WATTAGE 1/16W
J 2
(-1225 -625);
DISPLAY 0.404255 (-1225 -625);
FORCEPROP 1 LAST LOCATION R304
J 0
(-1600 -700);
DISPLAY 0.638298 (-1600 -700);
FORCEPROP 1 LASTPIN (-1500 -700) $PN 1
J 0
(-1488 -688);
DISPLAY 0.787234 (-1488 -688);
PAINT MONO (-1488 -688);
FORCEPROP 1 LASTPIN (-1300 -700) $PN 2
J 0
(-1338 -688);
DISPLAY 0.787234 (-1338 -688);
PAINT MONO (-1338 -688);
FORCEPROP 2 LAST CDS_LIB pure_quanta
J 0
(-1400 -700);
DISPLAY INVISIBLE (-1400 -700);
FORCEPROP 1 LAST PATH I102
J 0
(-1450 -550);
DISPLAY 0.978723 (-1450 -550);
PAINT WHITE (-1450 -550);
DISPLAY INVISIBLE (-1450 -550);
FORCEPROP 0 LAST $SEC 1
J 0
(-1450 -575);
DISPLAY 0.680851 (-1450 -575);
PAINT MONO (-1450 -575);
DISPLAY INVISIBLE (-1450 -575);
FORCEPROP 0 LAST CDS_SEC 1
J 0
(-1450 -575);
DISPLAY 1.021277 (-1450 -575);
DISPLAY INVISIBLE (-1450 -575);
FORCEADD OFFPAGE..1
(-2350 1050);
FORCEPROP 2 LAST $XR0 14 
J 0
(-2601 1050);
DISPLAY 0.638298 (-2601 1050);
PAINT MONO (-2601 1050);
FORCEPROP 2 LAST CDS_LIB standard
J 0
(-2350 1050);
PAINT MONO (-2350 1050);
DISPLAY INVISIBLE (-2350 1050);
FORCEPROP 1 LAST OFFPAGE TRUE
J 0
(-2025 925);
DISPLAY 0.872340 (-2025 925);
PAINT GREEN (-2025 925);
DISPLAY INVISIBLE (-2025 925);
FORCEPROP 1 LAST COMMENT_BODY TRUE
J 0
(-2225 950);
DISPLAY 0.872340 (-2225 950);
PAINT GREEN (-2225 950);
DISPLAY INVISIBLE (-2225 950);
FORCEPROP 2 LAST PATH I12
J 0
(-2300 1125);
DISPLAY 1.021277 (-2300 1125);
DISPLAY INVISIBLE (-2300 1125);
FORCEADD Q_RES..1
(-1400 1050);
FORCEPROP 1 LAST PART_NUMBER CS00002JB13
J 0
(-1500 1125);
DISPLAY 0.510638 (-1500 1125);
DISPLAY INVISIBLE (-1500 1125);
FORCEPROP 1 LAST MATERIAL CHIP
J 0
(-1500 1175);
DISPLAY 0.510638 (-1500 1175);
FORCEPROP 1 LAST TOLERANCE 5%
J 0
(-1225 1050);
DISPLAY 0.638298 (-1225 1050);
FORCEPROP 1 LAST VALUE 0
J 2
(-1250 1050);
DISPLAY 0.638298 (-1250 1050);
FORCEPROP 1 LAST WATTAGE 1/16W
J 2
(-1275 1175);
DISPLAY 0.510638 (-1275 1175);
FORCEPROP 1 LAST PACK_TYPE 0402LF
J 0
(-1250 1175);
DISPLAY 0.510638 (-1250 1175);
FORCEPROP 1 LAST $LOCATION R297
J 0
(-1600 1050);
DISPLAY 0.638298 (-1600 1050);
FORCEPROP 1 LASTPIN (-1500 1050) $PN 1
J 0
(-1488 1062);
DISPLAY 0.787234 (-1488 1062);
FORCEPROP 1 LASTPIN (-1300 1050) $PN 2
J 0
(-1338 1062);
DISPLAY 0.787234 (-1338 1062);
FORCEPROP 2 LAST CDS_LIB pure_quanta
J 0
(-1400 1050);
PAINT MONO (-1400 1050);
DISPLAY INVISIBLE (-1400 1050);
FORCEPROP 1 LAST PATH I23
J 0
(-1450 1200);
DISPLAY 0.978723 (-1450 1200);
PAINT WHITE (-1450 1200);
DISPLAY INVISIBLE (-1450 1200);
FORCEPROP 2 LAST CDS_LOCATION R297
J 0
(-1450 1250);
DISPLAY 1.021277 (-1450 1250);
DISPLAY INVISIBLE (-1450 1250);
FORCEPROP 2 LAST $SEC 1
J 0
(-1450 1250);
DISPLAY 0.680851 (-1450 1250);
PAINT MONO (-1450 1250);
DISPLAY INVISIBLE (-1450 1250);
FORCEPROP 2 LAST CDS_SEC 1
J 0
(-1450 1250);
DISPLAY 1.021277 (-1450 1250);
DISPLAY INVISIBLE (-1450 1250);
FORCEADD OFFPAGE..2
(925 -1400);
FORCEPROP 2 LAST $XR0 222 
J 0
(1114 -1400);
DISPLAY 0.638298 (1114 -1400);
PAINT MONO (1114 -1400);
FORCEPROP 2 LAST CDS_LIB standard
J 0
(925 -1400);
DISPLAY INVISIBLE (925 -1400);
FORCEPROP 1 LAST OFFPAGE TRUE
J 0
(1250 -1525);
DISPLAY 0.872340 (1250 -1525);
PAINT GREEN (1250 -1525);
DISPLAY INVISIBLE (1250 -1525);
FORCEPROP 1 LAST COMMENT_BODY TRUE
J 0
(880 -1495);
DISPLAY 0.872340 (880 -1495);
PAINT GREEN (880 -1495);
DISPLAY INVISIBLE (880 -1495);
FORCEPROP 2 LAST PATH I55
J 0
(1125 -1350);
DISPLAY 1.021277 (1125 -1350);
DISPLAY INVISIBLE (1125 -1350);
FORCEADD Q_RES..1
(-1400 575);
FORCEPROP 1 LAST PART_NUMBER CS00002JB13
J 0
(-1500 650);
DISPLAY 0.510638 (-1500 650);
DISPLAY INVISIBLE (-1500 650);
FORCEPROP 1 LAST PACK_TYPE 0402LF
J 0
(-1250 700);
DISPLAY 0.510638 (-1250 700);
FORCEPROP 1 LAST VALUE 0
J 2
(-1250 575);
DISPLAY 0.638298 (-1250 575);
FORCEPROP 1 LAST MATERIAL CHIP
J 0
(-1500 700);
DISPLAY 0.510638 (-1500 700);
FORCEPROP 1 LAST WATTAGE 1/16W
J 2
(-1275 700);
DISPLAY 0.510638 (-1275 700);
FORCEPROP 1 LAST TOLERANCE 5%
J 0
(-1225 575);
DISPLAY 0.638298 (-1225 575);
FORCEPROP 1 LAST $LOCATION R299
J 0
(-1600 575);
DISPLAY 0.638298 (-1600 575);
FORCEPROP 1 LASTPIN (-1500 575) $PN 1
J 0
(-1488 587);
DISPLAY 0.787234 (-1488 587);
FORCEPROP 1 LASTPIN (-1300 575) $PN 2
J 0
(-1338 587);
DISPLAY 0.787234 (-1338 587);
FORCEPROP 2 LAST CDS_LIB pure_quanta
J 0
(-1400 575);
PAINT MONO (-1400 575);
DISPLAY INVISIBLE (-1400 575);
FORCEPROP 1 LAST PATH I63
J 0
(-1450 725);
DISPLAY 0.978723 (-1450 725);
PAINT WHITE (-1450 725);
DISPLAY INVISIBLE (-1450 725);
FORCEPROP 2 LAST CDS_LOCATION R299
J 0
(-1450 775);
DISPLAY 1.021277 (-1450 775);
DISPLAY INVISIBLE (-1450 775);
FORCEPROP 2 LAST $SEC 1
J 0
(-1450 775);
DISPLAY 0.680851 (-1450 775);
PAINT MONO (-1450 775);
DISPLAY INVISIBLE (-1450 775);
FORCEPROP 2 LAST CDS_SEC 1
J 0
(-1450 775);
DISPLAY 1.021277 (-1450 775);
DISPLAY INVISIBLE (-1450 775);
FORCEADD OFFPAGE..1
(-2350 575);
FORCEPROP 2 LAST $XR0 45 
J 0
(-2601 575);
DISPLAY 0.638298 (-2601 575);
PAINT MONO (-2601 575);
FORCEPROP 2 LAST CDS_LIB standard
J 0
(-2350 575);
PAINT MONO (-2350 575);
DISPLAY INVISIBLE (-2350 575);
FORCEPROP 1 LAST OFFPAGE TRUE
J 0
(-2025 450);
DISPLAY 0.872340 (-2025 450);
PAINT GREEN (-2025 450);
DISPLAY INVISIBLE (-2025 450);
FORCEPROP 1 LAST COMMENT_BODY TRUE
J 0
(-2225 475);
DISPLAY 0.872340 (-2225 475);
PAINT GREEN (-2225 475);
DISPLAY INVISIBLE (-2225 475);
FORCEPROP 2 LAST PATH I64
J 0
(-2300 650);
DISPLAY 1.021277 (-2300 650);
DISPLAY INVISIBLE (-2300 650);
FORCEADD Q_RES..1
(-1400 1250);
FORCEPROP 1 LAST PART_NUMBER CS13012FB02
J 0
(-1475 1325);
DISPLAY 0.510638 (-1475 1325);
DISPLAY INVISIBLE (-1475 1325);
FORCEPROP 1 LAST WATTAGE 1/16W
J 2
(-1225 1375);
DISPLAY 0.510638 (-1225 1375);
FORCEPROP 1 LAST TOLERANCE 1%
J 0
(-1150 1250);
DISPLAY 0.638298 (-1150 1250);
FORCEPROP 1 LAST PACK_TYPE 0402LF
J 0
(-1200 1375);
DISPLAY 0.510638 (-1200 1375);
FORCEPROP 1 LAST VALUE 301
J 2
(-1175 1250);
DISPLAY 0.638298 (-1175 1250);
FORCEPROP 1 LAST MATERIAL CHIP
J 0
(-1475 1375);
DISPLAY 0.510638 (-1475 1375);
FORCEPROP 1 LAST $LOCATION R296
J 0
(-1600 1250);
DISPLAY 0.638298 (-1600 1250);
FORCEPROP 1 LASTPIN (-1500 1250) $PN 1
J 0
(-1488 1262);
DISPLAY 0.787234 (-1488 1262);
FORCEPROP 1 LASTPIN (-1300 1250) $PN 2
J 0
(-1338 1262);
DISPLAY 0.787234 (-1338 1262);
FORCEPROP 2 LAST CDS_LIB pure_quanta
J 0
(-1400 1250);
PAINT MONO (-1400 1250);
DISPLAY INVISIBLE (-1400 1250);
FORCEPROP 1 LAST PATH I65
J 0
(-1450 1400);
DISPLAY 0.978723 (-1450 1400);
PAINT WHITE (-1450 1400);
DISPLAY INVISIBLE (-1450 1400);
FORCEPROP 2 LAST CDS_LOCATION R296
J 0
(-1450 1450);
DISPLAY 1.021277 (-1450 1450);
DISPLAY INVISIBLE (-1450 1450);
FORCEPROP 2 LAST $SEC 1
J 0
(-1450 1450);
DISPLAY 0.680851 (-1450 1450);
PAINT MONO (-1450 1450);
DISPLAY INVISIBLE (-1450 1450);
FORCEPROP 2 LAST CDS_SEC 1
J 0
(-1450 1450);
DISPLAY 1.021277 (-1450 1450);
DISPLAY INVISIBLE (-1450 1450);
FORCEADD UNIVERSAL_POWER..1
(-1950 1350);
FORCEPROP 3 LASTPIN (-1950 1300) SIG_NAME PVNN_TERM_CPU0\g
J 0
(-1940 1310);
DISPLAY 0.659574 (-1940 1310);
PAINT MONO (-1940 1310);
DISPLAY INVISIBLE (-1940 1310);
FORCEPROP 1 LAST HDL_POWER PVNN_TERM_CPU0
J 1
(-1950 1400);
DISPLAY 0.872340 (-1950 1400);
PAINT GREEN (-1950 1400);
FORCEPROP 2 LAST CDS_LIB logical_power
J 0
(-1950 1350);
PAINT MONO (-1950 1350);
DISPLAY INVISIBLE (-1950 1350);
FORCEPROP 1 LAST PATH I66
J 0
(-1900 1375);
DISPLAY 0.872340 (-1900 1375);
PAINT AQUA (-1900 1375);
DISPLAY INVISIBLE (-1900 1375);
FORCEADD Q_RES..1
(-1400 775);
FORCEPROP 1 LAST PART_NUMBER CS13012FB02
J 0
(-1475 850);
DISPLAY 0.510638 (-1475 850);
DISPLAY INVISIBLE (-1475 850);
FORCEPROP 1 LAST VALUE 301
J 2
(-1175 775);
DISPLAY 0.638298 (-1175 775);
FORCEPROP 1 LAST MATERIAL CHIP
J 0
(-1475 900);
DISPLAY 0.510638 (-1475 900);
FORCEPROP 1 LAST TOLERANCE 1%
J 0
(-1150 775);
DISPLAY 0.638298 (-1150 775);
FORCEPROP 1 LAST WATTAGE 1/16W
J 2
(-1225 900);
DISPLAY 0.510638 (-1225 900);
FORCEPROP 1 LAST PACK_TYPE 0402LF
J 0
(-1200 900);
DISPLAY 0.510638 (-1200 900);
FORCEPROP 1 LAST $LOCATION R298
J 0
(-1600 775);
DISPLAY 0.638298 (-1600 775);
FORCEPROP 1 LASTPIN (-1500 775) $PN 1
J 0
(-1488 787);
DISPLAY 0.787234 (-1488 787);
FORCEPROP 1 LASTPIN (-1300 775) $PN 2
J 0
(-1338 787);
DISPLAY 0.787234 (-1338 787);
FORCEPROP 2 LAST CDS_LIB pure_quanta
J 0
(-1400 775);
PAINT MONO (-1400 775);
DISPLAY INVISIBLE (-1400 775);
FORCEPROP 1 LAST PATH I67
J 0
(-1450 925);
DISPLAY 0.978723 (-1450 925);
PAINT WHITE (-1450 925);
DISPLAY INVISIBLE (-1450 925);
FORCEPROP 2 LAST CDS_LOCATION R298
J 0
(-1450 975);
DISPLAY 1.021277 (-1450 975);
DISPLAY INVISIBLE (-1450 975);
FORCEPROP 2 LAST $SEC 1
J 0
(-1450 975);
DISPLAY 0.680851 (-1450 975);
PAINT MONO (-1450 975);
DISPLAY INVISIBLE (-1450 975);
FORCEPROP 2 LAST CDS_SEC 1
J 0
(-1450 975);
DISPLAY 1.021277 (-1450 975);
DISPLAY INVISIBLE (-1450 975);
FORCEADD UNIVERSAL_POWER..1
(-1950 875);
FORCEPROP 3 LASTPIN (-1950 825) SIG_NAME PVNN_TERM_CPU1\g
J 0
(-1940 835);
DISPLAY 0.659574 (-1940 835);
PAINT MONO (-1940 835);
DISPLAY INVISIBLE (-1940 835);
FORCEPROP 1 LAST HDL_POWER PVNN_TERM_CPU1
J 1
(-1950 925);
DISPLAY 0.872340 (-1950 925);
PAINT GREEN (-1950 925);
FORCEPROP 2 LAST CDS_LIB logical_power
J 0
(-1950 875);
PAINT MONO (-1950 875);
DISPLAY INVISIBLE (-1950 875);
FORCEPROP 1 LAST PATH I68
J 0
(-1900 900);
DISPLAY 0.872340 (-1900 900);
PAINT AQUA (-1900 900);
DISPLAY INVISIBLE (-1900 900);
FORCEADD Q_RES..1
(-1400 -25);
FORCEPROP 1 LAST PART_NUMBER CS13012FB02
J 0
(-1475 50);
DISPLAY 0.510638 (-1475 50);
DISPLAY INVISIBLE (-1475 50);
FORCEPROP 1 LAST TOLERANCE 1%
J 0
(-1150 -25);
DISPLAY 0.638298 (-1150 -25);
FORCEPROP 1 LAST MATERIAL CHIP
J 0
(-1475 100);
DISPLAY 0.510638 (-1475 100);
FORCEPROP 1 LAST WATTAGE 1/16W
J 2
(-1225 100);
DISPLAY 0.510638 (-1225 100);
FORCEPROP 1 LAST PACK_TYPE 0402LF
J 0
(-1200 100);
DISPLAY 0.510638 (-1200 100);
FORCEPROP 1 LAST VALUE 301
J 2
(-1175 -25);
DISPLAY 0.638298 (-1175 -25);
FORCEPROP 1 LAST $LOCATION R301
J 0
(-1600 -25);
DISPLAY 0.638298 (-1600 -25);
FORCEPROP 1 LASTPIN (-1500 -25) $PN 1
J 0
(-1488 -13);
DISPLAY 0.787234 (-1488 -13);
FORCEPROP 1 LASTPIN (-1300 -25) $PN 2
J 0
(-1338 -13);
DISPLAY 0.787234 (-1338 -13);
FORCEPROP 2 LAST CDS_LIB pure_quanta
J 0
(-1400 -25);
PAINT MONO (-1400 -25);
DISPLAY INVISIBLE (-1400 -25);
FORCEPROP 1 LAST PATH I73
J 0
(-1450 125);
DISPLAY 0.978723 (-1450 125);
PAINT WHITE (-1450 125);
DISPLAY INVISIBLE (-1450 125);
FORCEPROP 2 LAST CDS_LOCATION R301
J 0
(-1450 175);
DISPLAY 1.021277 (-1450 175);
DISPLAY INVISIBLE (-1450 175);
FORCEPROP 2 LAST $SEC 1
J 0
(-1450 175);
DISPLAY 0.680851 (-1450 175);
PAINT MONO (-1450 175);
DISPLAY INVISIBLE (-1450 175);
FORCEPROP 2 LAST CDS_SEC 1
J 0
(-1450 175);
DISPLAY 1.021277 (-1450 175);
DISPLAY INVISIBLE (-1450 175);
FORCEADD UNIVERSAL_POWER..1
(-1950 75);
FORCEPROP 3 LASTPIN (-1950 25) SIG_NAME PVNN_TERM_CPU0\g
J 0
(-1940 35);
DISPLAY 0.659574 (-1940 35);
PAINT MONO (-1940 35);
DISPLAY INVISIBLE (-1940 35);
FORCEPROP 1 LAST HDL_POWER PVNN_TERM_CPU0
J 1
(-1950 125);
DISPLAY 0.872340 (-1950 125);
PAINT GREEN (-1950 125);
FORCEPROP 2 LAST CDS_LIB logical_power
J 0
(-1950 75);
PAINT MONO (-1950 75);
DISPLAY INVISIBLE (-1950 75);
FORCEPROP 1 LAST PATH I74
J 0
(-1900 100);
DISPLAY 0.872340 (-1900 100);
PAINT AQUA (-1900 100);
DISPLAY INVISIBLE (-1900 100);
FORCEADD Q_RES..1
(-1400 -500);
FORCEPROP 1 LAST PART_NUMBER CS13012FB02
J 0
(-1475 -425);
DISPLAY 0.510638 (-1475 -425);
DISPLAY INVISIBLE (-1475 -425);
FORCEPROP 1 LAST MATERIAL CHIP
J 0
(-1475 -375);
DISPLAY 0.510638 (-1475 -375);
FORCEPROP 1 LAST WATTAGE 1/16W
J 2
(-1225 -375);
DISPLAY 0.510638 (-1225 -375);
FORCEPROP 1 LAST VALUE 301
J 2
(-1175 -500);
DISPLAY 0.638298 (-1175 -500);
FORCEPROP 1 LAST PACK_TYPE 0402LF
J 0
(-1200 -375);
DISPLAY 0.510638 (-1200 -375);
FORCEPROP 1 LAST TOLERANCE 1%
J 0
(-1150 -500);
DISPLAY 0.638298 (-1150 -500);
FORCEPROP 1 LAST $LOCATION R303
J 0
(-1600 -500);
DISPLAY 0.638298 (-1600 -500);
FORCEPROP 1 LASTPIN (-1500 -500) $PN 1
J 0
(-1488 -488);
DISPLAY 0.787234 (-1488 -488);
FORCEPROP 1 LASTPIN (-1300 -500) $PN 2
J 0
(-1338 -488);
DISPLAY 0.787234 (-1338 -488);
FORCEPROP 2 LAST CDS_LIB pure_quanta
J 0
(-1400 -500);
PAINT MONO (-1400 -500);
DISPLAY INVISIBLE (-1400 -500);
FORCEPROP 1 LAST PATH I76
J 0
(-1450 -350);
DISPLAY 0.978723 (-1450 -350);
PAINT WHITE (-1450 -350);
DISPLAY INVISIBLE (-1450 -350);
FORCEPROP 2 LAST CDS_LOCATION R303
J 0
(-1450 -300);
DISPLAY 1.021277 (-1450 -300);
DISPLAY INVISIBLE (-1450 -300);
FORCEPROP 2 LAST $SEC 1
J 0
(-1450 -300);
DISPLAY 0.680851 (-1450 -300);
PAINT MONO (-1450 -300);
DISPLAY INVISIBLE (-1450 -300);
FORCEPROP 2 LAST CDS_SEC 1
J 0
(-1450 -300);
DISPLAY 1.021277 (-1450 -300);
DISPLAY INVISIBLE (-1450 -300);
FORCEADD UNIVERSAL_POWER..1
(-1950 -400);
FORCEPROP 3 LASTPIN (-1950 -450) SIG_NAME PVNN_TERM_CPU1\g
J 0
(-1940 -440);
DISPLAY 0.659574 (-1940 -440);
PAINT MONO (-1940 -440);
DISPLAY INVISIBLE (-1940 -440);
FORCEPROP 1 LAST HDL_POWER PVNN_TERM_CPU1
J 1
(-1950 -350);
DISPLAY 0.872340 (-1950 -350);
PAINT GREEN (-1950 -350);
FORCEPROP 2 LAST CDS_LIB logical_power
J 0
(-1950 -400);
PAINT MONO (-1950 -400);
DISPLAY INVISIBLE (-1950 -400);
FORCEPROP 1 LAST PATH I78
J 0
(-1900 -375);
DISPLAY 0.872340 (-1900 -375);
PAINT AQUA (-1900 -375);
DISPLAY INVISIBLE (-1900 -375);
FORCEADD OFFPAGE..1
(-2350 -225);
FORCEPROP 2 LAST $XR0 16 
J 0
(-2601 -225);
DISPLAY 0.638298 (-2601 -225);
PAINT MONO (-2601 -225);
FORCEPROP 2 LAST CDS_LIB standard
J 0
(-2350 -225);
PAINT MONO (-2350 -225);
DISPLAY INVISIBLE (-2350 -225);
FORCEPROP 1 LAST OFFPAGE TRUE
J 0
(-2025 -350);
DISPLAY 0.872340 (-2025 -350);
PAINT GREEN (-2025 -350);
DISPLAY INVISIBLE (-2025 -350);
FORCEPROP 1 LAST COMMENT_BODY TRUE
J 0
(-2225 -325);
DISPLAY 0.872340 (-2225 -325);
PAINT GREEN (-2225 -325);
DISPLAY INVISIBLE (-2225 -325);
FORCEPROP 2 LAST PATH I79
J 0
(-2300 -150);
DISPLAY 1.021277 (-2300 -150);
DISPLAY INVISIBLE (-2300 -150);
FORCEADD OFFPAGE..1
(-2350 -700);
FORCEPROP 2 LAST $XR0 47 
J 0
(-2601 -700);
DISPLAY 0.638298 (-2601 -700);
PAINT MONO (-2601 -700);
FORCEPROP 2 LAST CDS_LIB standard
J 0
(-2350 -700);
PAINT MONO (-2350 -700);
DISPLAY INVISIBLE (-2350 -700);
FORCEPROP 1 LAST OFFPAGE TRUE
J 0
(-2025 -825);
DISPLAY 0.872340 (-2025 -825);
PAINT GREEN (-2025 -825);
DISPLAY INVISIBLE (-2025 -825);
FORCEPROP 1 LAST COMMENT_BODY TRUE
J 0
(-2225 -800);
DISPLAY 0.872340 (-2225 -800);
PAINT GREEN (-2225 -800);
DISPLAY INVISIBLE (-2225 -800);
FORCEPROP 2 LAST PATH I80
J 0
(-2300 -625);
DISPLAY 1.021277 (-2300 -625);
DISPLAY INVISIBLE (-2300 -625);
FORCEADD OFFPAGE..1
(-2350 -1400);
FORCEPROP 2 LAST $XR0 182 
J 0
(-2632 -1400);
DISPLAY 0.638298 (-2632 -1400);
PAINT MONO (-2632 -1400);
FORCEPROP 2 LAST CDS_LIB standard
J 0
(-2350 -1400);
PAINT MONO (-2350 -1400);
DISPLAY INVISIBLE (-2350 -1400);
FORCEPROP 1 LAST OFFPAGE TRUE
J 0
(-2025 -1525);
DISPLAY 0.872340 (-2025 -1525);
PAINT GREEN (-2025 -1525);
DISPLAY INVISIBLE (-2025 -1525);
FORCEPROP 1 LAST COMMENT_BODY TRUE
J 0
(-2225 -1500);
DISPLAY 0.872340 (-2225 -1500);
PAINT GREEN (-2225 -1500);
DISPLAY INVISIBLE (-2225 -1500);
FORCEPROP 2 LAST PATH I84
J 0
(-2300 -1325);
DISPLAY 1.021277 (-2300 -1325);
DISPLAY INVISIBLE (-2300 -1325);
FORCEADD Q_RES..1
(-775 -1400);
FORCEPROP 1 LAST PART_NUMBER CS03322FB03
J 0
(-825 -1350);
DISPLAY 0.404255 (-825 -1350);
DISPLAY INVISIBLE (-825 -1350);
FORCEPROP 1 LAST MATERIAL CHIP
J 0
(-825 -1325);
DISPLAY 0.404255 (-825 -1325);
FORCEPROP 1 LAST WATTAGE 1/16W
J 2
(-475 -1325);
DISPLAY 0.404255 (-475 -1325);
FORCEPROP 1 LAST PACK_TYPE 0402LF
J 0
(-700 -1325);
DISPLAY 0.404255 (-700 -1325);
FORCEPROP 1 LAST TOLERANCE 1%
J 0
(-550 -1400);
DISPLAY 0.510638 (-550 -1400);
FORCEPROP 1 LAST VALUE 33.2
J 2
(-575 -1400);
DISPLAY 0.510638 (-575 -1400);
FORCEPROP 1 LAST $LOCATION R315
J 0
(-975 -1400);
DISPLAY 0.638298 (-975 -1400);
FORCEPROP 1 LASTPIN (-875 -1400) $PN 1
J 0
(-863 -1388);
DISPLAY 0.787234 (-863 -1388);
FORCEPROP 1 LASTPIN (-675 -1400) $PN 2
J 0
(-713 -1388);
DISPLAY 0.787234 (-713 -1388);
FORCEPROP 2 LAST CDS_LIB pure_quanta
J 0
(-775 -1400);
PAINT MONO (-775 -1400);
DISPLAY INVISIBLE (-775 -1400);
FORCEPROP 1 LAST PATH I92
J 0
(-825 -1250);
DISPLAY 0.978723 (-825 -1250);
PAINT WHITE (-825 -1250);
DISPLAY INVISIBLE (-825 -1250);
FORCEPROP 2 LAST CDS_LOCATION R315
J 0
(-825 -1200);
DISPLAY 1.021277 (-825 -1200);
DISPLAY INVISIBLE (-825 -1200);
FORCEPROP 2 LAST $SEC 1
J 0
(-825 -1200);
DISPLAY 0.680851 (-825 -1200);
PAINT MONO (-825 -1200);
DISPLAY INVISIBLE (-825 -1200);
FORCEPROP 2 LAST CDS_SEC 1
J 0
(-825 -1200);
DISPLAY 1.021277 (-825 -1200);
DISPLAY INVISIBLE (-825 -1200);
FORCEADD OFFPAGE..2
(925 1050);
FORCEPROP 2 LAST $XR0 226 
J 0
(1114 1050);
DISPLAY 0.638298 (1114 1050);
PAINT MONO (1114 1050);
FORCEPROP 2 LAST CDS_LIB standard
J 0
(925 1050);
DISPLAY INVISIBLE (925 1050);
FORCEPROP 1 LAST OFFPAGE TRUE
J 0
(1250 925);
DISPLAY 0.872340 (1250 925);
PAINT GREEN (1250 925);
DISPLAY INVISIBLE (1250 925);
FORCEPROP 1 LAST COMMENT_BODY TRUE
J 0
(880 955);
DISPLAY 0.872340 (880 955);
PAINT GREEN (880 955);
DISPLAY INVISIBLE (880 955);
FORCEPROP 2 LAST PATH I98
J 0
(1275 1100);
DISPLAY 1.021277 (1275 1100);
DISPLAY INVISIBLE (1275 1100);
FORCEADD QUANTA_TITLE_BLOCK_C..1
(6150 -3775);
FORCEPROP 0 LAST CDS_CON_LAST_MODIFIED Fri Aug 25 14:01:38 2023
J 0
(4265 -3760);
PAINT MONO (4265 -3760);
DISPLAY INVISIBLE (4265 -3760);
FORCEPROP 2 LAST CUSTOM_TXT_CDS <XR_PAGE_TITLE>
J 0
(-1740 1475);
DISPLAY 0.638298 (-1740 1475);
PAINT PINK (-1740 1475);
DISPLAY INVISIBLE (-1740 1475);
FORCEPROP 2 LAST CUSTOM_TXT_CDS <CON_PAGE_NUM> OF <CON_TOTAL_PAGES>
J 0
(5704 -3757);
DISPLAY 0.978723 (5704 -3757);
FORCEPROP 2 LAST CUSTOM_TXT_CDS <Q_REV>
J 0
(5966 -3672);
DISPLAY 1.212766 (5966 -3672);
FORCEPROP 2 LAST CUSTOM_TXT_CDS <Q_PROJ>
J 0
(3768 -3673);
DISPLAY 1.212766 (3768 -3673);
FORCEPROP 2 LAST CUSTOM_TXT_CDS <Q_NUMBER>
J 0
(4747 -3672);
DISPLAY 1.212766 (4747 -3672);
FORCEPROP 2 LAST CUSTOM_TXT_CDS <NAME_1>
J 0
(2975 -3600);
FORCEPROP 2 LAST CUSTOM_TXT_CDS <NAME_2>
J 0
(2975 -3725);
FORCEPROP 2 LAST CUSTOM_TXT_CDS <CON_LAST_MODIFIED>
J 0
(4265 -3760);
DISPLAY 0.978723 (4265 -3760);
FORCEPROP 1 LAST Q_TITLE SPR CPU0 & 1 - CATERR/RMCA
J 0
(-3116 -3774);
DISPLAY 2.446809 (-3116 -3774);
PAINT GREEN (-3116 -3774);
FORCEPROP 1 LAST Q_DEPT 
J 1
(2387 -3726);
DISPLAY 1.957447 (2387 -3726);
PAINT GREEN (2387 -3726);
FORCEPROP 2 LAST CDS_XR_PAGE_TITLE CR-118 : @S9S_MB_2U_LIB.S9S_MB_2U(SCH_1):PAGE118
J 0
(-1740 1475);
DISPLAY 0.638298 (-1740 1475);
PAINT PINK (-1740 1475);
DISPLAY INVISIBLE (-1740 1475);
FORCEPROP 2 LAST PAGE_BORDER TRUE
J 0
(-1740 1475);
DISPLAY 0.638298 (-1740 1475);
PAINT PINK (-1740 1475);
DISPLAY INVISIBLE (-1740 1475);
FORCEPROP 1 LAST COMMENT_BODY TRUE
J 0
(6162 -3788);
DISPLAY 0.978723 (6162 -3788);
PAINT GREEN (6162 -3788);
DISPLAY INVISIBLE (6162 -3788);
FORCEPROP 1 LAST CDS_LMAN_SYM_OUTLINE -9475,6775,100,-125
J 0
(6150 -3775);
DISPLAY 0.468085 (6150 -3775);
PAINT GREEN (6150 -3775);
DISPLAY INVISIBLE (6150 -3775);
FORCEPROP 2 LAST CDS_LIB pure_quanta
J 0
(6150 -3775);
PAINT MONO (6150 -3775);
DISPLAY INVISIBLE (6150 -3775);
WIRE 16 -1 (-1950 -450)(-1950 -500);
WIRE 16 -1 (-1950 25)(-1950 -25);
WIRE 16 -1 (-1950 825)(-1950 775);
WIRE 16 -1 (-1950 1300)(-1950 1250);
WIRE 16 -1 (-1500 1050)(-2300 1050);
FORCEPROP 2 LAST SIG_NAME H_CPU0_CATERR_LVC1_R_N
J 0
(-2235 1060);
DISPLAY 0.553191 (-2235 1060);
PAINT WHITE (-2235 1060);
WIRE 16 2175 (-1650 -575)(-1075 -575);
WIRE 16 2175 (-1075 -575)(-1075 -725);
WIRE 16 2175 (-1650 -575)(-1650 -725);
WIRE 16 2175 (-1650 -725)(-1075 -725);
WIRE 16 -1 (-2300 -1400)(-875 -1400);
FORCEPROP 2 LAST SIG_NAME PWRGD_CPUPWRGD_GTL
J 0
(-2235 -1390);
DISPLAY 0.553191 (-2235 -1390);
PAINT WHITE (-2235 -1390);
WIRE 16 -1 (-675 -1400)(875 -1400);
FORCEPROP 2 LAST SIG_NAME PWRGD_CPUPWRGD_LVC1_R
J 0
(-75 -1390);
DISPLAY 0.553191 (-75 -1390);
PAINT WHITE (-75 -1390);
WIRE 16 -1 (-1500 -700)(-2300 -700);
FORCEPROP 2 LAST SIG_NAME H_CPU1_RMCA_LVC1_R_N
J 0
(-2235 -690);
DISPLAY 0.553191 (-2235 -690);
PAINT WHITE (-2235 -690);
WIRE 16 -1 (-1025 -25)(-1300 -25);
WIRE 16 -1 (-1300 -225)(-1025 -225);
WIRE 16 -1 (-1025 -25)(-1025 -225);
WIRE 16 -1 (-1025 -225)(-750 -225);
WIRE 16 -1 (875 -225)(-750 -225);
FORCEPROP 2 LAST SIG_NAME H_CPU_RMCA_LVC1_R_N
J 0
(-35 -215);
DISPLAY 0.553191 (-35 -215);
PAINT WHITE (-35 -215);
WIRE 16 -1 (-750 -225)(-750 -700);
WIRE 16 -1 (-1025 -700)(-1300 -700);
WIRE 16 -1 (-1025 -700)(-750 -700);
WIRE 16 -1 (-1025 -700)(-1025 -500);
WIRE 16 -1 (-1025 -500)(-1300 -500);
WIRE 16 -1 (-1950 -500)(-1500 -500);
WIRE 16 -1 (-1500 -225)(-2300 -225);
FORCEPROP 2 LAST SIG_NAME H_CPU0_RMCA_LVC1_R_N
J 0
(-2235 -215);
DISPLAY 0.553191 (-2235 -215);
PAINT WHITE (-2235 -215);
WIRE 16 2175 (-1625 -250)(-1050 -250);
WIRE 16 2175 (-1050 -100)(-1050 -250);
WIRE 16 2175 (-1625 -100)(-1625 -250);
WIRE 16 2175 (-1625 -100)(-1050 -100);
WIRE 16 -1 (-1950 -25)(-1500 -25);
WIRE 16 -1 (-1950 775)(-1500 775);
WIRE 16 -1 (-1025 775)(-1300 775);
WIRE 16 -1 (-1025 575)(-1300 575);
WIRE 16 -1 (-1025 575)(-1025 775);
WIRE 16 -1 (-1025 1250)(-1300 1250);
WIRE 16 -1 (-1025 575)(-775 575);
WIRE 16 -1 (-775 1050)(-775 575);
WIRE 16 -1 (875 1050)(-775 1050);
FORCEPROP 2 LAST SIG_NAME H_CPU_CATERR_LVC1_R_N
J 0
(-75 1060);
DISPLAY 0.553191 (-75 1060);
PAINT WHITE (-75 1060);
WIRE 16 -1 (-1025 1050)(-1300 1050);
WIRE 16 -1 (-1025 1050)(-1025 1250);
WIRE 16 -1 (-1025 1050)(-775 1050);
WIRE 16 -1 (-1950 1250)(-1500 1250);
WIRE 16 -1 (-1500 575)(-2300 575);
FORCEPROP 2 LAST SIG_NAME H_CPU1_CATERR_LVC1_R_N
J 0
(-2235 585);
DISPLAY 0.553191 (-2235 585);
PAINT WHITE (-2235 585);
DOT 1 (-1025 -700);
DOT 1 (-775 1050);
DOT 1 (-1025 -225);
DOT 1 (-750 -225);
DOT 1 (-1025 575);
DOT 1 (-1025 1050);
FORCENOTE
20211129 R302,R304 CHANGE TO 0 OHM
(-2025 -850) 0;
DISPLAY LEFT (-2025 -850);
DISPLAY 1.063830 (-2025 -850);
PAINT WHITE (-2025 -850);
QUIT
